FILE_TYPE=LIBRARY_PARTS;
primitive 'Q_SP_RES4P';
  pin
    '2B':
      PIN_NUMBER='(2B)';
      BIDIRECTIONAL='TRUE';
      INPUT_LOAD='(-0.01,0.01)';
      OUTPUT_LOAD='(1.0,-1.0)';
    '1B':
      PIN_NUMBER='(1B)';
      BIDIRECTIONAL='TRUE';
      INPUT_LOAD='(-0.01,0.01)';
      OUTPUT_LOAD='(1.0,-1.0)';
    '2A':
      PIN_NUMBER='(2A)';
      BIDIRECTIONAL='TRUE';
      INPUT_LOAD='(-0.01,0.01)';
      OUTPUT_LOAD='(1.0,-1.0)';
    '1A':
      PIN_NUMBER='(1A)';
      BIDIRECTIONAL='TRUE';
      INPUT_LOAD='(-0.01,0.01)';
      OUTPUT_LOAD='(1.0,-1.0)';
  end_pin;
  body
    PART_NAME='Q_SP_RES4P';
    BODY_NAME='Q_SP_RES4P';
    PHYS_DES_PREFIX='R';
    CLASS='DISCRETE';
  end_body;
end_primitive;

END.
